# S9S_MB_2U (Grand Teton) — schematic netlist excerpt (pin names and nets, part order shuffled) for the footprints in the layout excerpt that follows; sources: Cadence DE-HDL packaged netlist, KiCad conversion of 03242023_DA0F0TMBIJ0_F0T_Motherboard_J_brd_V01_OCP.brd

PC2347  Q_CAP  1NF 50V 10% EMPTY  pkg 0402  page 302 : A = HSC_OCREF ; B = AGND_HSC
R205  Q_RES  1.5K 1% CHIP  pkg 0402LF  page 123 : A = H_CPU0_MEMTRIP_LVC1_R_N ; B = H_CPU0_MEMTRIP_OUT_VT_R_N

(kicad_pcb
	(version 20260206)
	(generator "pcbnew")
	(generator_version "10.0")
	(general
		(thickness 1.6)
		(legacy_teardrops no)
	)
	(paper "A4")
	(title_block
		(title "03242023_DA0F0TMBIJ0_F0T_Motherboard_J_brd_V01_OCP.brd")
		(comment 1 "Grand Teton / footprints 1787-1788 of 6105")
	)
	(layers
		(0 "F.Cu" signal "TOP")
		(4 "In1.Cu" signal "GND")
		(6 "In2.Cu" signal "IN1")
		(8 "In3.Cu" signal "GND1")
		(10 "In4.Cu" signal "IN2")
		(12 "In5.Cu" signal "GND2")
		(14 "In6.Cu" signal "IN3")
		(16 "In7.Cu" signal "GND3")
		(18 "In8.Cu" signal "VCC")
		(20 "In9.Cu" signal "VCC1")
		(22 "In10.Cu" signal "GND4")
		(24 "In11.Cu" signal "IN4")
		(26 "In12.Cu" signal "GND5")
		(28 "In13.Cu" signal "IN5")
		(30 "In14.Cu" signal "GND6")
		(32 "In15.Cu" signal "IN6")
		(34 "In16.Cu" signal "GND7")
		(2 "B.Cu" signal "BOTTOM")
		(9 "F.Adhes" user "F.Adhesive")
		(11 "B.Adhes" user "B.Adhesive")
		(13 "F.Paste" user "Package Geometry/Pastemask Top")
		(15 "B.Paste" user "Package Geometry/Pastemask Bottom")
		(5 "F.SilkS" user "Ref Des/Silkscreen Top")
		(7 "B.SilkS" user "Ref Des/Silkscreen Bottom")
		(1 "F.Mask" user "Board Geometry/Soldermask Top")
		(3 "B.Mask" user "Board Geometry/Soldermask Bottom")
		(17 "Dwgs.User" user "User.Drawings")
		(19 "Cmts.User" user "User.Comments")
		(21 "Eco1.User" user "User.Eco1")
		(23 "Eco2.User" user "User.Eco2")
		(25 "Edge.Cuts" user "Board Geometry/Outline")
		(27 "Margin" user)
		(31 "F.CrtYd" user "Package Geometry/Place Bound Top")
		(29 "B.CrtYd" user "Package Geometry/Place Bound Bottom")
		(35 "F.Fab" user "Ref Des/Assembly Top")
		(33 "B.Fab" user "Ref Des/Assembly Bottom")
	)
	(footprint ""
		(layer "F.Cu")
		(at 194.853306 -399.743422 180)
		(property "Reference" "PC2347"
			(at 0 0 180)
			(layer "F.SilkS")
			(hide yes)
			(effects
				(font
					(size 1.27 1.27)
				)
			)
		)
		(property "Value" ""
			(at 0 0 180)
			(layer "F.Fab")
			(effects
				(font
					(size 1.27 1.27)
				)
			)
		)
		(duplicate_pad_numbers_are_jumpers no)
		(fp_line
			(start 0.7874 0.4064)
			(end -0.7874 0.4064)
			(stroke
				(width 0.1524)
				(type default)
			)
			(layer "F.SilkS")
		)
		(fp_line
			(start 0.7874 -0.4064)
			(end 0.7874 0.4064)
			(stroke
				(width 0.1524)
				(type default)
			)
			(layer "F.SilkS")
		)
		(fp_line
			(start -0.7874 0.4064)
			(end -0.7874 -0.4064)
			(stroke
				(width 0.1524)
				(type default)
			)
			(layer "F.SilkS")
		)
		(fp_line
			(start -0.7874 -0.4064)
			(end 0.7874 -0.4064)
			(stroke
				(width 0.1524)
				(type default)
			)
			(layer "F.SilkS")
		)
		(fp_line
			(start 0.67945 0.3048)
			(end 0.120396 0.3048)
			(stroke
				(width 0.1)
				(type default)
			)
			(layer "F.Fab")
		)
		(fp_line
			(start 0.67945 -0.3048)
			(end 0.67945 0.3048)
			(stroke
				(width 0.1)
				(type default)
			)
			(layer "F.Fab")
		)
		(fp_line
			(start 0.12065 -0.2794)
			(end 0.12065 -0.3048)
			(stroke
				(width 0.1)
				(type default)
			)
			(layer "F.Fab")
		)
		(fp_line
			(start 0.12065 -0.3048)
			(end 0.67945 -0.3048)
			(stroke
				(width 0.1)
				(type default)
			)
			(layer "F.Fab")
		)
		(fp_line
			(start 0.120396 0.3048)
			(end 0.120396 0.2794)
			(stroke
				(width 0.1)
				(type default)
			)
			(layer "F.Fab")
		)
		(fp_line
			(start 0.120396 0.2794)
			(end -0.12065 0.2794)
			(stroke
				(width 0.1)
				(type default)
			)
			(layer "F.Fab")
		)
		(fp_line
			(start -0.12065 0.3048)
			(end -0.67945 0.3048)
			(stroke
				(width 0.1)
				(type default)
			)
			(layer "F.Fab")
		)
		(fp_line
			(start -0.12065 0.2794)
			(end -0.12065 0.3048)
			(stroke
				(width 0.1)
				(type default)
			)
			(layer "F.Fab")
		)
		(fp_line
			(start -0.12065 -0.2794)
			(end 0.12065 -0.2794)
			(stroke
				(width 0.1)
				(type default)
			)
			(layer "F.Fab")
		)
		(fp_line
			(start -0.12065 -0.305054)
			(end -0.12065 -0.2794)
			(stroke
				(width 0.1)
				(type default)
			)
			(layer "F.Fab")
		)
		(fp_line
			(start -0.67945 0.3048)
			(end -0.67945 -0.305054)
			(stroke
				(width 0.1)
				(type default)
			)
			(layer "F.Fab")
		)
		(fp_line
			(start -0.67945 -0.305054)
			(end -0.12065 -0.305054)
			(stroke
				(width 0.1)
				(type default)
			)
			(layer "F.Fab")
		)
		(pad "1" smd circle
			(at -0.40005 0 180)
			(size 0 0)
			(layers "F.Cu" "F.Mask" "F.Paste")
			(net "HSC_OCREF")
		)
		(pad "2" smd circle
			(at 0.40005 0 180)
			(size 0 0)
			(layers "F.Cu" "F.Mask" "F.Paste")
			(net "AGND_HSC")
		)
	)
	(footprint ""
		(layer "F.Cu")
		(at 129.46888 -100.167948 90)
		(property "Reference" "R205"
			(at 0 0 90)
			(layer "F.SilkS")
			(hide yes)
			(effects
				(font
					(size 1.27 1.27)
				)
			)
		)
		(property "Value" ""
			(at 0 0 90)
			(layer "F.Fab")
			(effects
				(font
					(size 1.27 1.27)
				)
			)
		)
		(duplicate_pad_numbers_are_jumpers no)
		(fp_line
			(start 0.7874 -0.4064)
			(end 0.7874 0.4064)
			(stroke
				(width 0.1524)
				(type default)
			)
			(layer "F.SilkS")
		)
		(fp_line
			(start -0.7874 -0.4064)
			(end 0.7874 -0.4064)
			(stroke
				(width 0.1524)
				(type default)
			)
			(layer "F.SilkS")
		)
		(fp_line
			(start 0.7874 0.4064)
			(end -0.7874 0.4064)
			(stroke
				(width 0.1524)
				(type default)
			)
			(layer "F.SilkS")
		)
		(fp_line
			(start -0.7874 0.4064)
			(end -0.7874 -0.4064)
			(stroke
				(width 0.1524)
				(type default)
			)
			(layer "F.SilkS")
		)
		(fp_line
			(start -0.12065 -0.305054)
			(end -0.12065 -0.2794)
			(stroke
				(width 0.1)
				(type default)
			)
			(layer "F.Fab")
		)
		(fp_line
			(start -0.67945 -0.305054)
			(end -0.12065 -0.305054)
			(stroke
				(width 0.1)
				(type default)
			)
			(layer "F.Fab")
		)
		(fp_line
			(start 0.67945 -0.3048)
			(end 0.67945 0.3048)
			(stroke
				(width 0.1)
				(type default)
			)
			(layer "F.Fab")
		)
		(fp_line
			(start 0.12065 -0.3048)
			(end 0.67945 -0.3048)
			(stroke
				(width 0.1)
				(type default)
			)
			(layer "F.Fab")
		)
		(fp_line
			(start 0.12065 -0.2794)
			(end 0.12065 -0.3048)
			(stroke
				(width 0.1)
				(type default)
			)
			(layer "F.Fab")
		)
		(fp_line
			(start -0.12065 -0.2794)
			(end 0.12065 -0.2794)
			(stroke
				(width 0.1)
				(type default)
			)
			(layer "F.Fab")
		)
		(fp_line
			(start 0.120396 0.2794)
			(end -0.12065 0.2794)
			(stroke
				(width 0.1)
				(type default)
			)
			(layer "F.Fab")
		)
		(fp_line
			(start -0.12065 0.2794)
			(end -0.12065 0.3048)
			(stroke
				(width 0.1)
				(type default)
			)
			(layer "F.Fab")
		)
		(fp_line
			(start 0.67945 0.3048)
			(end 0.120396 0.3048)
			(stroke
				(width 0.1)
				(type default)
			)
			(layer "F.Fab")
		)
		(fp_line
			(start 0.120396 0.3048)
			(end 0.120396 0.2794)
			(stroke
				(width 0.1)
				(type default)
			)
			(layer "F.Fab")
		)
		(fp_line
			(start -0.12065 0.3048)
			(end -0.67945 0.3048)
			(stroke
				(width 0.1)
				(type default)
			)
			(layer "F.Fab")
		)
		(fp_line
			(start -0.67945 0.3048)
			(end -0.67945 -0.305054)
			(stroke
				(width 0.1)
				(type default)
			)
			(layer "F.Fab")
		)
		(pad "1" smd circle
			(at -0.40005 0 90)
			(size 0 0)
			(layers "F.Cu" "F.Mask" "F.Paste")
			(net "H_CPU0_MEMTRIP_LVC1_R_N")
		)
		(pad "2" smd circle
			(at 0.40005 0 90)
			(size 0 0)
			(layers "F.Cu" "F.Mask" "F.Paste")
			(net "H_CPU0_MEMTRIP_OUT_VT_R_N")
		)
	)
)
